# SCM (Grand Teton) — schematic netlist excerpt (pin names and nets, part order shuffled) for the footprints in the layout excerpt that follows; sources: Cadence DE-HDL packaged netlist, KiCad conversion of 12092022_DA0F0TMDCD0_F0T_Management_Board_D_brd_V3_OCP.brd

D18  Q_LED  IC  pkg SMLF  page 49 : A = P3V3_AUX ; C = FM_UARTSW_LSB_R1_N
R813  Q_RES  33.2 1% CHIP  pkg 0402LF  page 49 : A = HDD_LED_BUF ; B = HDD_LED_BUF_R

(kicad_pcb
	(version 20260206)
	(generator "pcbnew")
	(generator_version "10.0")
	(general
		(thickness 1.6)
		(legacy_teardrops no)
	)
	(paper "A4")
	(title_block
		(title "12092022_DA0F0TMDCD0_F0T_Management_Board_D_brd_V3_OCP.brd")
		(comment 1 "Grand Teton / footprints 716-717 of 1440")
	)
	(layers
		(0 "F.Cu" signal "TOP")
		(4 "In1.Cu" signal "GND")
		(6 "In2.Cu" signal "IN1")
		(8 "In3.Cu" signal "GND1")
		(10 "In4.Cu" signal "IN2")
		(12 "In5.Cu" signal "VCC")
		(14 "In6.Cu" signal "VCC1")
		(16 "In7.Cu" signal "IN3")
		(18 "In8.Cu" signal "GND2")
		(20 "In9.Cu" signal "IN4")
		(22 "In10.Cu" signal "GND3")
		(2 "B.Cu" signal "BOTTOM")
		(9 "F.Adhes" user "F.Adhesive")
		(11 "B.Adhes" user "B.Adhesive")
		(13 "F.Paste" user "Package Geometry/Pastemask Top")
		(15 "B.Paste" user "Package Geometry/Pastemask Bottom")
		(5 "F.SilkS" user "Ref Des/Silkscreen Top")
		(7 "B.SilkS" user "Ref Des/Silkscreen Bottom")
		(1 "F.Mask" user "Board Geometry/Soldermask Top")
		(3 "B.Mask" user "Board Geometry/Soldermask Bottom")
		(17 "Dwgs.User" user "User.Drawings")
		(19 "Cmts.User" user "User.Comments")
		(21 "Eco1.User" user "User.Eco1")
		(23 "Eco2.User" user "User.Eco2")
		(25 "Edge.Cuts" user "Board Geometry/Outline")
		(27 "Margin" user)
		(31 "F.CrtYd" user "Package Geometry/Place Bound Top")
		(29 "B.CrtYd" user "Package Geometry/Place Bound Bottom")
		(35 "F.Fab" user "Ref Des/Assembly Top")
		(33 "B.Fab" user "Ref Des/Assembly Bottom")
	)
	(footprint ""
		(layer "F.Cu")
		(at 75.057 -21.336 180)
		(property "Reference" "D18"
			(at 1.143 1.11633 0)
			(unlocked yes)
			(layer "F.SilkS")
			(effects
				(font
					(size 0.7874 0.5842)
					(thickness 0.1524)
				)
				(justify left)
			)
		)
		(property "Value" ""
			(at 0 0 180)
			(layer "F.Fab")
			(effects
				(font
					(size 1.27 1.27)
				)
			)
		)
		(duplicate_pad_numbers_are_jumpers no)
		(fp_line
			(start 1.16078 0.4826)
			(end -0.64008 0.4826)
			(stroke
				(width 0.1524)
				(type default)
			)
			(layer "F.SilkS")
		)
		(fp_line
			(start 1.16078 -0.4826)
			(end 1.16078 0.4826)
			(stroke
				(width 0.1524)
				(type default)
			)
			(layer "F.SilkS")
		)
		(fp_line
			(start 1.03378 0.4826)
			(end -0.79248 0.4826)
			(stroke
				(width 0.1524)
				(type default)
			)
			(layer "F.SilkS")
		)
		(fp_line
			(start 1.03378 -0.4826)
			(end 1.03378 0.4826)
			(stroke
				(width 0.1524)
				(type default)
			)
			(layer "F.SilkS")
		)
		(fp_line
			(start 0.90678 0.4826)
			(end -0.90678 0.4826)
			(stroke
				(width 0.1524)
				(type default)
			)
			(layer "F.SilkS")
		)
		(fp_line
			(start 0.90678 -0.4826)
			(end 0.90678 0.4826)
			(stroke
				(width 0.1524)
				(type default)
			)
			(layer "F.SilkS")
		)
		(fp_line
			(start -0.64008 -0.4826)
			(end 1.16078 -0.4826)
			(stroke
				(width 0.1524)
				(type default)
			)
			(layer "F.SilkS")
		)
		(fp_line
			(start -0.79248 -0.4826)
			(end 1.03378 -0.4826)
			(stroke
				(width 0.1524)
				(type default)
			)
			(layer "F.SilkS")
		)
		(fp_line
			(start -0.89408 -0.4826)
			(end 0.90678 -0.4826)
			(stroke
				(width 0.1524)
				(type default)
			)
			(layer "F.SilkS")
		)
		(fp_line
			(start -0.90678 0.4826)
			(end -0.90678 -0.4699)
			(stroke
				(width 0.1524)
				(type default)
			)
			(layer "F.SilkS")
		)
		(fp_line
			(start 0.499872 0.249936)
			(end -0.499872 0.249936)
			(stroke
				(width 0.1)
				(type default)
			)
			(layer "F.Fab")
		)
		(fp_line
			(start 0.499872 -0.249936)
			(end 0.499872 0.249936)
			(stroke
				(width 0.1)
				(type default)
			)
			(layer "F.Fab")
		)
		(fp_line
			(start -0.499872 0.249936)
			(end -0.499872 -0.249936)
			(stroke
				(width 0.1)
				(type default)
			)
			(layer "F.Fab")
		)
		(fp_line
			(start -0.499872 -0.249936)
			(end 0.499872 -0.249936)
			(stroke
				(width 0.1)
				(type default)
			)
			(layer "F.Fab")
		)
		(pad "A" smd rect
			(at -0.47498 0 180)
			(size 0.6096 0.7112)
			(layers "F.Cu" "F.Mask" "F.Paste")
			(net "P3V3_AUX")
		)
		(pad "C" smd rect
			(at 0.47498 0 180)
			(size 0.6096 0.7112)
			(layers "F.Cu" "F.Mask" "F.Paste")
			(net "FM_UARTSW_LSB_R1_N")
		)
	)
	(footprint ""
		(layer "F.Cu")
		(at 27.559 -10.287 -90)
		(property "Reference" "R813"
			(at 0 0 270)
			(layer "F.SilkS")
			(hide yes)
			(effects
				(font
					(size 1.27 1.27)
				)
			)
		)
		(property "Value" ""
			(at 0 0 270)
			(layer "F.Fab")
			(effects
				(font
					(size 1.27 1.27)
				)
			)
		)
		(duplicate_pad_numbers_are_jumpers no)
		(fp_line
			(start -0.7874 0.4064)
			(end -0.7874 -0.4064)
			(stroke
				(width 0.1524)
				(type default)
			)
			(layer "F.SilkS")
		)
		(fp_line
			(start 0.7874 0.4064)
			(end -0.7874 0.4064)
			(stroke
				(width 0.1524)
				(type default)
			)
			(layer "F.SilkS")
		)
		(fp_line
			(start -0.7874 -0.4064)
			(end 0.7874 -0.4064)
			(stroke
				(width 0.1524)
				(type default)
			)
			(layer "F.SilkS")
		)
		(fp_line
			(start 0.7874 -0.4064)
			(end 0.7874 0.4064)
			(stroke
				(width 0.1524)
				(type default)
			)
			(layer "F.SilkS")
		)
		(fp_line
			(start -0.67945 0.3048)
			(end -0.67945 -0.305054)
			(stroke
				(width 0.1)
				(type default)
			)
			(layer "F.Fab")
		)
		(fp_line
			(start -0.12065 0.3048)
			(end -0.67945 0.3048)
			(stroke
				(width 0.1)
				(type default)
			)
			(layer "F.Fab")
		)
		(fp_line
			(start 0.120396 0.3048)
			(end 0.120396 0.2794)
			(stroke
				(width 0.1)
				(type default)
			)
			(layer "F.Fab")
		)
		(fp_line
			(start 0.67945 0.3048)
			(end 0.120396 0.3048)
			(stroke
				(width 0.1)
				(type default)
			)
			(layer "F.Fab")
		)
		(fp_line
			(start -0.12065 0.2794)
			(end -0.12065 0.3048)
			(stroke
				(width 0.1)
				(type default)
			)
			(layer "F.Fab")
		)
		(fp_line
			(start 0.120396 0.2794)
			(end -0.12065 0.2794)
			(stroke
				(width 0.1)
				(type default)
			)
			(layer "F.Fab")
		)
		(fp_line
			(start -0.12065 -0.2794)
			(end 0.12065 -0.2794)
			(stroke
				(width 0.1)
				(type default)
			)
			(layer "F.Fab")
		)
		(fp_line
			(start 0.12065 -0.2794)
			(end 0.12065 -0.3048)
			(stroke
				(width 0.1)
				(type default)
			)
			(layer "F.Fab")
		)
		(fp_line
			(start 0.12065 -0.3048)
			(end 0.67945 -0.3048)
			(stroke
				(width 0.1)
				(type default)
			)
			(layer "F.Fab")
		)
		(fp_line
			(start 0.67945 -0.3048)
			(end 0.67945 0.3048)
			(stroke
				(width 0.1)
				(type default)
			)
			(layer "F.Fab")
		)
		(fp_line
			(start -0.67945 -0.305054)
			(end -0.12065 -0.305054)
			(stroke
				(width 0.1)
				(type default)
			)
			(layer "F.Fab")
		)
		(fp_line
			(start -0.12065 -0.305054)
			(end -0.12065 -0.2794)
			(stroke
				(width 0.1)
				(type default)
			)
			(layer "F.Fab")
		)
		(pad "1" smd circle
			(at -0.40005 0 270)
			(size 0 0)
			(layers "F.Cu" "F.Mask" "F.Paste")
			(net "HDD_LED_BUF")
		)
		(pad "2" smd circle
			(at 0.40005 0 270)
			(size 0 0)
			(layers "F.Cu" "F.Mask" "F.Paste")
			(net "HDD_LED_BUF_R")
		)
	)
)
